(kicad_pcb
	(version 20260206)
	(generator "pcbnew")
	(generator_version "10.0")
	(general
		(thickness 1.6)
		(legacy_teardrops no)
	)
	(paper "A4")
	(title_block
		(title "01162023_DA0F0TEBIF0_F0T_Expander_BD_F_brd_V02_OCP.brd")
		(comment 1 "Grand Teton / footprints 41-47 of 9728")
	)
	(layers
		(0 "F.Cu" signal "TOP")
		(4 "In1.Cu" signal "GND")
		(6 "In2.Cu" signal "VCC")
		(8 "In3.Cu" signal "VCC1")
		(10 "In4.Cu" signal "GND1")
		(12 "In5.Cu" signal "IN1")
		(14 "In6.Cu" signal "GND2")
		(16 "In7.Cu" signal "IN2")
		(18 "In8.Cu" signal "GND3")
		(20 "In9.Cu" signal "IN3")
		(22 "In10.Cu" signal "GND4")
		(24 "In11.Cu" signal "IN4")
		(26 "In12.Cu" signal "GND5")
		(28 "In13.Cu" signal "IN5")
		(30 "In14.Cu" signal "GND6")
		(32 "In15.Cu" signal "IN6")
		(34 "In16.Cu" signal "GND7")
		(2 "B.Cu" signal "BOTTOM")
		(9 "F.Adhes" user "F.Adhesive")
		(11 "B.Adhes" user "B.Adhesive")
		(13 "F.Paste" user "Package Geometry/Pastemask Top")
		(15 "B.Paste" user "Package Geometry/Pastemask Bottom")
		(5 "F.SilkS" user "Ref Des/Silkscreen Top")
		(7 "B.SilkS" user "Ref Des/Silkscreen Bottom")
		(1 "F.Mask" user "Board Geometry/Soldermask Top")
		(3 "B.Mask" user "Board Geometry/Soldermask Bottom")
		(17 "Dwgs.User" user "User.Drawings")
		(19 "Cmts.User" user "User.Comments")
		(21 "Eco1.User" user "User.Eco1")
		(23 "Eco2.User" user "User.Eco2")
		(25 "Edge.Cuts" user "Board Geometry/Outline")
		(27 "Margin" user)
		(31 "F.CrtYd" user "Package Geometry/Place Bound Top")
		(29 "B.CrtYd" user "Package Geometry/Place Bound Bottom")
		(35 "F.Fab" user "Ref Des/Assembly Top")
		(33 "B.Fab" user "Ref Des/Assembly Bottom")
	)
	(footprint ""
		(layer "F.Cu")
		(at 245.77675 -258.034536 -90)
		(property "Reference" "R6525"
			(at 0 0 270)
			(layer "F.SilkS")
			(hide yes)
			(effects
				(font
					(size 1.27 1.27)
				)
			)
		)
		(property "Value" ""
			(at 0 0 270)
			(layer "F.Fab")
			(effects
				(font
					(size 1.27 1.27)
				)
			)
		)
		(duplicate_pad_numbers_are_jumpers no)
		(fp_line
			(start -0.7874 0.4064)
			(end -0.7874 -0.4064)
			(stroke
				(width 0.1524)
				(type default)
			)
			(layer "F.SilkS")
		)
		(fp_line
			(start 0.7874 0.4064)
			(end -0.7874 0.4064)
			(stroke
				(width 0.1524)
				(type default)
			)
			(layer "F.SilkS")
		)
		(fp_line
			(start -0.7874 -0.4064)
			(end 0.7874 -0.4064)
			(stroke
				(width 0.1524)
				(type default)
			)
			(layer "F.SilkS")
		)
		(fp_line
			(start 0.7874 -0.4064)
			(end 0.7874 0.4064)
			(stroke
				(width 0.1524)
				(type default)
			)
			(layer "F.SilkS")
		)
		(fp_line
			(start -0.67945 0.3048)
			(end -0.67945 -0.305054)
			(stroke
				(width 0.1)
				(type default)
			)
			(layer "F.Fab")
		)
		(fp_line
			(start -0.12065 0.3048)
			(end -0.67945 0.3048)
			(stroke
				(width 0.1)
				(type default)
			)
			(layer "F.Fab")
		)
		(fp_line
			(start 0.120396 0.3048)
			(end 0.120396 0.2794)
			(stroke
				(width 0.1)
				(type default)
			)
			(layer "F.Fab")
		)
		(fp_line
			(start 0.67945 0.3048)
			(end 0.120396 0.3048)
			(stroke
				(width 0.1)
				(type default)
			)
			(layer "F.Fab")
		)
		(fp_line
			(start -0.12065 0.2794)
			(end -0.12065 0.3048)
			(stroke
				(width 0.1)
				(type default)
			)
			(layer "F.Fab")
		)
		(fp_line
			(start 0.120396 0.2794)
			(end -0.12065 0.2794)
			(stroke
				(width 0.1)
				(type default)
			)
			(layer "F.Fab")
		)
		(fp_line
			(start -0.12065 -0.2794)
			(end 0.12065 -0.2794)
			(stroke
				(width 0.1)
				(type default)
			)
			(layer "F.Fab")
		)
		(fp_line
			(start 0.12065 -0.2794)
			(end 0.12065 -0.3048)
			(stroke
				(width 0.1)
				(type default)
			)
			(layer "F.Fab")
		)
		(fp_line
			(start 0.12065 -0.3048)
			(end 0.67945 -0.3048)
			(stroke
				(width 0.1)
				(type default)
			)
			(layer "F.Fab")
		)
		(fp_line
			(start 0.67945 -0.3048)
			(end 0.67945 0.3048)
			(stroke
				(width 0.1)
				(type default)
			)
			(layer "F.Fab")
		)
		(fp_line
			(start -0.67945 -0.305054)
			(end -0.12065 -0.305054)
			(stroke
				(width 0.1)
				(type default)
			)
			(layer "F.Fab")
		)
		(fp_line
			(start -0.12065 -0.305054)
			(end -0.12065 -0.2794)
			(stroke
				(width 0.1)
				(type default)
			)
			(layer "F.Fab")
		)
		(pad "1" smd circle
			(at -0.40005 0 270)
			(size 0 0)
			(layers "F.Cu" "F.Mask" "F.Paste")
			(net "P1V25_SERDES_VDDPLL_PEX2")
		)
		(pad "2" smd circle
			(at 0.40005 0 270)
			(size 0 0)
			(layers "F.Cu" "F.Mask" "F.Paste")
			(net "P1V25_SERDES_VDDPLL_PEX2_C4")
		)
	)
	(footprint ""
		(layer "F.Cu")
		(at 453.17283 -258.331208 -90)
		(property "Reference" "R6552"
			(at 0 0 270)
			(layer "F.SilkS")
			(hide yes)
			(effects
				(font
					(size 1.27 1.27)
				)
			)
		)
		(property "Value" ""
			(at 0 0 270)
			(layer "F.Fab")
			(effects
				(font
					(size 1.27 1.27)
				)
			)
		)
		(duplicate_pad_numbers_are_jumpers no)
		(fp_line
			(start -0.7874 0.4064)
			(end -0.7874 -0.4064)
			(stroke
				(width 0.1524)
				(type default)
			)
			(layer "F.SilkS")
		)
		(fp_line
			(start 0.7874 0.4064)
			(end -0.7874 0.4064)
			(stroke
				(width 0.1524)
				(type default)
			)
			(layer "F.SilkS")
		)
		(fp_line
			(start -0.7874 -0.4064)
			(end 0.7874 -0.4064)
			(stroke
				(width 0.1524)
				(type default)
			)
			(layer "F.SilkS")
		)
		(fp_line
			(start 0.7874 -0.4064)
			(end 0.7874 0.4064)
			(stroke
				(width 0.1524)
				(type default)
			)
			(layer "F.SilkS")
		)
		(fp_line
			(start -0.67945 0.3048)
			(end -0.67945 -0.305054)
			(stroke
				(width 0.1)
				(type default)
			)
			(layer "F.Fab")
		)
		(fp_line
			(start -0.12065 0.3048)
			(end -0.67945 0.3048)
			(stroke
				(width 0.1)
				(type default)
			)
			(layer "F.Fab")
		)
		(fp_line
			(start 0.120396 0.3048)
			(end 0.120396 0.2794)
			(stroke
				(width 0.1)
				(type default)
			)
			(layer "F.Fab")
		)
		(fp_line
			(start 0.67945 0.3048)
			(end 0.120396 0.3048)
			(stroke
				(width 0.1)
				(type default)
			)
			(layer "F.Fab")
		)
		(fp_line
			(start -0.12065 0.2794)
			(end -0.12065 0.3048)
			(stroke
				(width 0.1)
				(type default)
			)
			(layer "F.Fab")
		)
		(fp_line
			(start 0.120396 0.2794)
			(end -0.12065 0.2794)
			(stroke
				(width 0.1)
				(type default)
			)
			(layer "F.Fab")
		)
		(fp_line
			(start -0.12065 -0.2794)
			(end 0.12065 -0.2794)
			(stroke
				(width 0.1)
				(type default)
			)
			(layer "F.Fab")
		)
		(fp_line
			(start 0.12065 -0.2794)
			(end 0.12065 -0.3048)
			(stroke
				(width 0.1)
				(type default)
			)
			(layer "F.Fab")
		)
		(fp_line
			(start 0.12065 -0.3048)
			(end 0.67945 -0.3048)
			(stroke
				(width 0.1)
				(type default)
			)
			(layer "F.Fab")
		)
		(fp_line
			(start 0.67945 -0.3048)
			(end 0.67945 0.3048)
			(stroke
				(width 0.1)
				(type default)
			)
			(layer "F.Fab")
		)
		(fp_line
			(start -0.67945 -0.305054)
			(end -0.12065 -0.305054)
			(stroke
				(width 0.1)
				(type default)
			)
			(layer "F.Fab")
		)
		(fp_line
			(start -0.12065 -0.305054)
			(end -0.12065 -0.2794)
			(stroke
				(width 0.1)
				(type default)
			)
			(layer "F.Fab")
		)
		(pad "1" smd circle
			(at -0.40005 0 270)
			(size 0 0)
			(layers "F.Cu" "F.Mask" "F.Paste")
			(net "P1V25_SERDES_VDDPLL_PEX3")
		)
		(pad "2" smd circle
			(at 0.40005 0 270)
			(size 0 0)
			(layers "F.Cu" "F.Mask" "F.Paste")
			(net "P1V25_SERDES_VDDPLL_PEX3_C1")
		)
	)
	(footprint ""
		(layer "F.Cu")
		(at 357.44277 -398.180052 90)
		(property "Reference" "R6701"
			(at 0 0 90)
			(layer "F.SilkS")
			(hide yes)
			(effects
				(font
					(size 1.27 1.27)
				)
			)
		)
		(property "Value" ""
			(at 0 0 90)
			(layer "F.Fab")
			(effects
				(font
					(size 1.27 1.27)
				)
			)
		)
		(duplicate_pad_numbers_are_jumpers no)
		(fp_line
			(start 0.7874 -0.4064)
			(end 0.7874 0.4064)
			(stroke
				(width 0.1524)
				(type default)
			)
			(layer "F.SilkS")
		)
		(fp_line
			(start -0.7874 -0.4064)
			(end 0.7874 -0.4064)
			(stroke
				(width 0.1524)
				(type default)
			)
			(layer "F.SilkS")
		)
		(fp_line
			(start 0.7874 0.4064)
			(end -0.7874 0.4064)
			(stroke
				(width 0.1524)
				(type default)
			)
			(layer "F.SilkS")
		)
		(fp_line
			(start -0.7874 0.4064)
			(end -0.7874 -0.4064)
			(stroke
				(width 0.1524)
				(type default)
			)
			(layer "F.SilkS")
		)
		(fp_line
			(start -0.12065 -0.305054)
			(end -0.12065 -0.2794)
			(stroke
				(width 0.1)
				(type default)
			)
			(layer "F.Fab")
		)
		(fp_line
			(start -0.67945 -0.305054)
			(end -0.12065 -0.305054)
			(stroke
				(width 0.1)
				(type default)
			)
			(layer "F.Fab")
		)
		(fp_line
			(start 0.67945 -0.3048)
			(end 0.67945 0.3048)
			(stroke
				(width 0.1)
				(type default)
			)
			(layer "F.Fab")
		)
		(fp_line
			(start 0.12065 -0.3048)
			(end 0.67945 -0.3048)
			(stroke
				(width 0.1)
				(type default)
			)
			(layer "F.Fab")
		)
		(fp_line
			(start 0.12065 -0.2794)
			(end 0.12065 -0.3048)
			(stroke
				(width 0.1)
				(type default)
			)
			(layer "F.Fab")
		)
		(fp_line
			(start -0.12065 -0.2794)
			(end 0.12065 -0.2794)
			(stroke
				(width 0.1)
				(type default)
			)
			(layer "F.Fab")
		)
		(fp_line
			(start 0.120396 0.2794)
			(end -0.12065 0.2794)
			(stroke
				(width 0.1)
				(type default)
			)
			(layer "F.Fab")
		)
		(fp_line
			(start -0.12065 0.2794)
			(end -0.12065 0.3048)
			(stroke
				(width 0.1)
				(type default)
			)
			(layer "F.Fab")
		)
		(fp_line
			(start 0.67945 0.3048)
			(end 0.120396 0.3048)
			(stroke
				(width 0.1)
				(type default)
			)
			(layer "F.Fab")
		)
		(fp_line
			(start 0.120396 0.3048)
			(end 0.120396 0.2794)
			(stroke
				(width 0.1)
				(type default)
			)
			(layer "F.Fab")
		)
		(fp_line
			(start -0.12065 0.3048)
			(end -0.67945 0.3048)
			(stroke
				(width 0.1)
				(type default)
			)
			(layer "F.Fab")
		)
		(fp_line
			(start -0.67945 0.3048)
			(end -0.67945 -0.305054)
			(stroke
				(width 0.1)
				(type default)
			)
			(layer "F.Fab")
		)
		(pad "1" smd circle
			(at -0.40005 0 90)
			(size 0 0)
			(layers "F.Cu" "F.Mask" "F.Paste")
			(net "MB_3V3IO_RSVD3_ISO")
		)
		(pad "2" smd circle
			(at 0.40005 0 90)
			(size 0 0)
			(layers "F.Cu" "F.Mask" "F.Paste")
			(net "P3V3_AUX")
		)
	)
	(footprint ""
		(layer "F.Cu")
		(at 440.689746 -298.885102 -90)
		(property "Reference" "R3992"
			(at 0 0 270)
			(layer "F.SilkS")
			(hide yes)
			(effects
				(font
					(size 1.27 1.27)
				)
			)
		)
		(property "Value" ""
			(at 0 0 270)
			(layer "F.Fab")
			(effects
				(font
					(size 1.27 1.27)
				)
			)
		)
		(duplicate_pad_numbers_are_jumpers no)
		(fp_line
			(start -0.7874 0.4064)
			(end -0.7874 -0.4064)
			(stroke
				(width 0.1524)
				(type default)
			)
			(layer "F.SilkS")
		)
		(fp_line
			(start 0.7874 0.4064)
			(end -0.7874 0.4064)
			(stroke
				(width 0.1524)
				(type default)
			)
			(layer "F.SilkS")
		)
		(fp_line
			(start -0.7874 -0.4064)
			(end 0.7874 -0.4064)
			(stroke
				(width 0.1524)
				(type default)
			)
			(layer "F.SilkS")
		)
		(fp_line
			(start 0.7874 -0.4064)
			(end 0.7874 0.4064)
			(stroke
				(width 0.1524)
				(type default)
			)
			(layer "F.SilkS")
		)
		(fp_line
			(start -0.67945 0.3048)
			(end -0.67945 -0.305054)
			(stroke
				(width 0.1)
				(type default)
			)
			(layer "F.Fab")
		)
		(fp_line
			(start -0.12065 0.3048)
			(end -0.67945 0.3048)
			(stroke
				(width 0.1)
				(type default)
			)
			(layer "F.Fab")
		)
		(fp_line
			(start 0.120396 0.3048)
			(end 0.120396 0.2794)
			(stroke
				(width 0.1)
				(type default)
			)
			(layer "F.Fab")
		)
		(fp_line
			(start 0.67945 0.3048)
			(end 0.120396 0.3048)
			(stroke
				(width 0.1)
				(type default)
			)
			(layer "F.Fab")
		)
		(fp_line
			(start -0.12065 0.2794)
			(end -0.12065 0.3048)
			(stroke
				(width 0.1)
				(type default)
			)
			(layer "F.Fab")
		)
		(fp_line
			(start 0.120396 0.2794)
			(end -0.12065 0.2794)
			(stroke
				(width 0.1)
				(type default)
			)
			(layer "F.Fab")
		)
		(fp_line
			(start -0.12065 -0.2794)
			(end 0.12065 -0.2794)
			(stroke
				(width 0.1)
				(type default)
			)
			(layer "F.Fab")
		)
		(fp_line
			(start 0.12065 -0.2794)
			(end 0.12065 -0.3048)
			(stroke
				(width 0.1)
				(type default)
			)
			(layer "F.Fab")
		)
		(fp_line
			(start 0.12065 -0.3048)
			(end 0.67945 -0.3048)
			(stroke
				(width 0.1)
				(type default)
			)
			(layer "F.Fab")
		)
		(fp_line
			(start 0.67945 -0.3048)
			(end 0.67945 0.3048)
			(stroke
				(width 0.1)
				(type default)
			)
			(layer "F.Fab")
		)
		(fp_line
			(start -0.67945 -0.305054)
			(end -0.12065 -0.305054)
			(stroke
				(width 0.1)
				(type default)
			)
			(layer "F.Fab")
		)
		(fp_line
			(start -0.12065 -0.305054)
			(end -0.12065 -0.2794)
			(stroke
				(width 0.1)
				(type default)
			)
			(layer "F.Fab")
		)
		(pad "1" smd circle
			(at -0.40005 0 270)
			(size 0 0)
			(layers "F.Cu" "F.Mask" "F.Paste")
			(net "I2C_PEX3_HOST_SCL")
		)
		(pad "2" smd circle
			(at 0.40005 0 270)
			(size 0 0)
			(layers "F.Cu" "F.Mask" "F.Paste")
			(net "I2C_PEX3_HOST_R_SCL")
		)
	)
	(footprint ""
		(layer "F.Cu")
		(at 340.458044 -350.098614 90)
		(property "Reference" "C577"
			(at 0 0 90)
			(layer "F.SilkS")
			(hide yes)
			(effects
				(font
					(size 1.27 1.27)
				)
			)
		)
		(property "Value" ""
			(at 0 0 90)
			(layer "F.Fab")
			(effects
				(font
					(size 1.27 1.27)
				)
			)
		)
		(duplicate_pad_numbers_are_jumpers no)
		(fp_line
			(start 0.299974 -0.150114)
			(end 0.299974 0.150114)
			(stroke
				(width 0.1)
				(type default)
			)
			(layer "F.Fab")
		)
		(fp_line
			(start -0.299974 -0.150114)
			(end 0.299974 -0.150114)
			(stroke
				(width 0.1)
				(type default)
			)
			(layer "F.Fab")
		)
		(fp_line
			(start 0.299974 0.150114)
			(end -0.299974 0.150114)
			(stroke
				(width 0.1)
				(type default)
			)
			(layer "F.Fab")
		)
		(fp_line
			(start -0.299974 0.150114)
			(end -0.299974 -0.150114)
			(stroke
				(width 0.1)
				(type default)
			)
			(layer "F.Fab")
		)
		(pad "1" smd rect
			(at -0.2667 0 90)
			(size 0.3048 0.381)
			(layers "F.Cu" "F.Mask" "F.Paste")
			(net "P5E_PEX2_STN6_TX_DP<98>")
		)
		(pad "2" smd rect
			(at 0.2667 0 90)
			(size 0.3048 0.381)
			(layers "F.Cu" "F.Mask" "F.Paste")
			(net "P5E_PEX2_STN6_TX_C_DP<98>")
		)
	)
	(footprint ""
		(layer "F.Cu")
		(at 130.25882 -319.545462 90)
		(property "Reference" "L29"
			(at 3.089402 2.267458 0)
			(unlocked yes)
			(layer "F.SilkS")
			(effects
				(font
					(size 0.7874 0.5842)
					(thickness 0.1524)
				)
				(justify left)
			)
		)
		(property "Value" ""
			(at 0 0 90)
			(layer "F.Fab")
			(effects
				(font
					(size 1.27 1.27)
				)
			)
		)
		(duplicate_pad_numbers_are_jumpers no)
		(fp_line
			(start 2.248154 -4.9911)
			(end -2.248154 -4.9911)
			(stroke
				(width 0.1524)
				(type default)
			)
			(layer "F.SilkS")
		)
		(fp_line
			(start -2.248154 -4.9911)
			(end -2.248154 -1.61925)
			(stroke
				(width 0.1524)
				(type default)
			)
			(layer "F.SilkS")
		)
		(fp_line
			(start 2.248154 -1.663192)
			(end 2.248154 -4.9911)
			(stroke
				(width 0.1524)
				(type default)
			)
			(layer "F.SilkS")
		)
		(fp_line
			(start -2.248154 1.564894)
			(end -2.248154 4.9911)
			(stroke
				(width 0.1524)
				(type default)
			)
			(layer "F.SilkS")
		)
		(fp_line
			(start 2.248154 4.9911)
			(end 2.248154 1.553972)
			(stroke
				(width 0.1524)
				(type default)
			)
			(layer "F.SilkS")
		)
		(fp_line
			(start -2.248154 4.9911)
			(end 2.248154 4.9911)
			(stroke
				(width 0.1524)
				(type default)
			)
			(layer "F.SilkS")
		)
		(fp_line
			(start 1.700022 -0.899922)
			(end -1.700022 -0.899922)
			(stroke
				(width 0.1)
				(type default)
			)
			(layer "F.Fab")
		)
		(fp_line
			(start -1.700022 -0.899922)
			(end -1.700022 0.899922)
			(stroke
				(width 0.1)
				(type default)
			)
			(layer "F.Fab")
		)
		(fp_line
			(start 1.700022 0.899922)
			(end 1.700022 -0.899922)
			(stroke
				(width 0.1)
				(type default)
			)
			(layer "F.Fab")
		)
		(fp_line
			(start -1.700022 0.899922)
			(end 1.700022 0.899922)
			(stroke
				(width 0.1)
				(type default)
			)
			(layer "F.Fab")
		)
		(pad "1" smd rect
			(at -1.575054 0 90)
			(size 1.1684 9.8044)
			(layers "F.Cu" "F.Mask" "F.Paste")
			(net "P0V8_PEX1")
		)
		(pad "2" smd rect
			(at 1.575054 0 90)
			(size 1.1684 9.8044)
			(layers "F.Cu" "F.Mask" "F.Paste")
			(net "P0V8_SERDES_VDDA_PEX1")
		)
	)
	(footprint ""
		(layer "F.Cu")
		(at 383.59842 -350.098614 90)
		(property "Reference" "C790"
			(at 0 0 90)
			(layer "F.SilkS")
			(hide yes)
			(effects
				(font
					(size 1.27 1.27)
				)
			)
		)
		(property "Value" ""
			(at 0 0 90)
			(layer "F.Fab")
			(effects
				(font
					(size 1.27 1.27)
				)
			)
		)
		(duplicate_pad_numbers_are_jumpers no)
		(fp_line
			(start 0.299974 -0.150114)
			(end 0.299974 0.150114)
			(stroke
				(width 0.1)
				(type default)
			)
			(layer "F.Fab")
		)
		(fp_line
			(start -0.299974 -0.150114)
			(end 0.299974 -0.150114)
			(stroke
				(width 0.1)
				(type default)
			)
			(layer "F.Fab")
		)
		(fp_line
			(start 0.299974 0.150114)
			(end -0.299974 0.150114)
			(stroke
				(width 0.1)
				(type default)
			)
			(layer "F.Fab")
		)
		(fp_line
			(start -0.299974 0.150114)
			(end -0.299974 -0.150114)
			(stroke
				(width 0.1)
				(type default)
			)
			(layer "F.Fab")
		)
		(pad "1" smd rect
			(at -0.2667 0 90)
			(size 0.3048 0.381)
			(layers "F.Cu" "F.Mask" "F.Paste")
			(net "P5E_PEX3_STN6_TX_DP<97>")
		)
		(pad "2" smd rect
			(at 0.2667 0 90)
			(size 0.3048 0.381)
			(layers "F.Cu" "F.Mask" "F.Paste")
			(net "P5E_PEX3_STN6_TX_C_DP<97>")
		)
	)
)
